# BASEBOARD_FAB2 (Tioga Pass) — schematic netlist excerpt (pin names and nets, part order shuffled) for the footprints in the layout excerpt that follows; sources: Cadence DE-HDL packaged netlist, KiCad conversion of Wiwynn_Tioga_Pass_MB.brd

C2D44  CAP_A  22.0UF 4V 20% X6S  pkg 0603V  page 225 : A = PVDDQ_GHJ ; B = GND
R4E9  RES  49.9 1% EMPTY  pkg 0402  page 201 : A = PVCCIO_CPU0 ; B = SVID_CLK0_CPU0_R
R1U58  RES  0.0 5% CHIP  pkg 0402  page 152 : A = H_CPU0_MEMDEF_MEMHOT_G_N ; B = H_CPU0_MEMDEF_MEMHOT_G_R_N

(kicad_pcb
	(version 20260206)
	(generator "pcbnew")
	(generator_version "10.0")
	(general
		(thickness 1.6)
		(legacy_teardrops no)
	)
	(paper "A4")
	(title_block
		(title "Wiwynn_Tioga_Pass_MB.brd")
		(comment 1 "Tioga Pass / footprints 765-767 of 4770")
	)
	(layers
		(0 "F.Cu" signal "TOP")
		(4 "In1.Cu" signal "L2GND")
		(6 "In2.Cu" signal "L3")
		(8 "In3.Cu" signal "L4GND")
		(10 "In4.Cu" signal "L5")
		(12 "In5.Cu" signal "L6GND")
		(14 "In6.Cu" signal "L7VCC")
		(16 "In7.Cu" signal "L8VCC")
		(18 "In8.Cu" signal "L9GND")
		(20 "In9.Cu" signal "L10")
		(22 "In10.Cu" signal "L11GND")
		(24 "In11.Cu" signal "L12")
		(26 "In12.Cu" signal "L13GND")
		(2 "B.Cu" signal "BOTTOM")
		(9 "F.Adhes" user "F.Adhesive")
		(11 "B.Adhes" user "B.Adhesive")
		(13 "F.Paste" user "Package Geometry/Pastemask Top")
		(15 "B.Paste" user "Package Geometry/Pastemask Bottom")
		(5 "F.SilkS" user "Ref Des/Silkscreen Top")
		(7 "B.SilkS" user "Ref Des/Silkscreen Bottom")
		(1 "F.Mask" user "Board Geometry/Soldermask Top")
		(3 "B.Mask" user "Board Geometry/Soldermask Bottom")
		(17 "Dwgs.User" user "User.Drawings")
		(19 "Cmts.User" user "User.Comments")
		(21 "Eco1.User" user "User.Eco1")
		(23 "Eco2.User" user "User.Eco2")
		(25 "Edge.Cuts" user "Board Geometry/Outline")
		(27 "Margin" user)
		(31 "F.CrtYd" user "Package Geometry/Place Bound Top")
		(29 "B.CrtYd" user "Package Geometry/Place Bound Bottom")
		(35 "F.Fab" user "Ref Des/Assembly Top")
		(33 "B.Fab" user "Ref Des/Assembly Bottom")
	)
	(footprint ""
		(layer "F.Cu")
		(at 437.769 -13.843)
		(property "Reference" "R1U58"
			(at 0 0 0)
			(layer "F.SilkS")
			(hide yes)
			(effects
				(font
					(size 1.27 1.27)
				)
			)
		)
		(property "Value" ""
			(at 0 0 0)
			(layer "F.Fab")
			(effects
				(font
					(size 1.27 1.27)
				)
			)
		)
		(duplicate_pad_numbers_are_jumpers no)
		(fp_poly
			(pts
				(xy -0.2794 -0.1016) (xy 0.2794 -0.1016) (xy 0.2794 0.9906) (xy -0.2794 0.9906)
			)
			(stroke
				(width 0)
				(type default)
			)
			(fill no)
			(layer "F.CrtYd")
		)
		(fp_line
			(start -0.2794 -0.1016)
			(end -0.2794 0.9906)
			(stroke
				(width 0.1)
				(type default)
			)
			(layer "F.Fab")
		)
		(fp_line
			(start -0.2794 0.9906)
			(end 0.2794 0.9906)
			(stroke
				(width 0.1)
				(type default)
			)
			(layer "F.Fab")
		)
		(fp_line
			(start 0.2794 -0.1016)
			(end -0.2794 -0.1016)
			(stroke
				(width 0.1)
				(type default)
			)
			(layer "F.Fab")
		)
		(fp_line
			(start 0.2794 0.9906)
			(end 0.2794 -0.1016)
			(stroke
				(width 0.1)
				(type default)
			)
			(layer "F.Fab")
		)
		(pad "1" smd rect
			(at 0 0)
			(size 0.508 0.508)
			(layers "F.Cu" "F.Mask" "F.Paste")
			(net "H_CPU0_MEMDEF_MEMHOT_G_N")
		)
		(pad "2" smd rect
			(at 0 0.889)
			(size 0.508 0.508)
			(layers "F.Cu" "F.Mask" "F.Paste")
			(net "H_CPU0_MEMDEF_MEMHOT_G_R_N")
		)
		(zone
			(layer "F.Cu")
			(hatch none 0.5)
			(connect_pads
				(clearance 0)
			)
			(min_thickness 0.25)
			(keepout
				(tracks allowed)
				(vias not_allowed)
				(pads allowed)
				(copperpour not_allowed)
				(footprints allowed)
			)
			(placement
				(enabled no)
				(sheetname "")
			)
			(fill
				(thermal_gap 0.5)
				(thermal_bridge_width 0.5)
				(island_removal_mode 0)
			)
			(polygon
				(pts
					(xy 437.515 -13.589) (xy 438.023 -13.589) (xy 438.023 -13.208) (xy 437.515 -13.208)
				)
			)
		)
		(zone
			(layer "F.Cu")
			(hatch none 0.5)
			(connect_pads
				(clearance 0)
			)
			(min_thickness 0.25)
			(keepout
				(tracks not_allowed)
				(vias allowed)
				(pads allowed)
				(copperpour not_allowed)
				(footprints allowed)
			)
			(placement
				(enabled no)
				(sheetname "")
			)
			(fill
				(thermal_gap 0.5)
				(thermal_bridge_width 0.5)
				(island_removal_mode 0)
			)
			(polygon
				(pts
					(xy 437.515 -13.208) (xy 438.023 -13.208) (xy 438.023 -13.589) (xy 437.515 -13.589)
				)
			)
		)
	)
	(footprint ""
		(layer "F.Cu")
		(at 183.007 -61.976 180)
		(property "Reference" "R4E9"
			(at 0 0 180)
			(layer "F.SilkS")
			(hide yes)
			(effects
				(font
					(size 1.27 1.27)
				)
			)
		)
		(property "Value" ""
			(at 0 0 180)
			(layer "F.Fab")
			(effects
				(font
					(size 1.27 1.27)
				)
			)
		)
		(duplicate_pad_numbers_are_jumpers no)
		(fp_rect
			(start 0.2794 -0.1016)
			(end -0.2794 0.9906)
			(stroke
				(width 0)
				(type default)
			)
			(fill no)
			(layer "F.CrtYd")
		)
		(fp_line
			(start 0.2794 0.9906)
			(end 0.2794 -0.1016)
			(stroke
				(width 0.1)
				(type default)
			)
			(layer "F.Fab")
		)
		(fp_line
			(start 0.2794 -0.1016)
			(end -0.2794 -0.1016)
			(stroke
				(width 0.1)
				(type default)
			)
			(layer "F.Fab")
		)
		(fp_line
			(start -0.2794 0.9906)
			(end 0.2794 0.9906)
			(stroke
				(width 0.1)
				(type default)
			)
			(layer "F.Fab")
		)
		(fp_line
			(start -0.2794 -0.1016)
			(end -0.2794 0.9906)
			(stroke
				(width 0.1)
				(type default)
			)
			(layer "F.Fab")
		)
		(pad "1" smd rect
			(at 0 0 180)
			(size 0.508 0.508)
			(layers "F.Cu" "F.Mask" "F.Paste")
			(net "PVCCIO_CPU0")
		)
		(pad "2" smd rect
			(at 0 0.889 180)
			(size 0.508 0.508)
			(layers "F.Cu" "F.Mask" "F.Paste")
			(net "SVID_CLK0_CPU0_R")
		)
		(zone
			(layer "F.Cu")
			(hatch none 0.5)
			(connect_pads
				(clearance 0)
			)
			(min_thickness 0.25)
			(keepout
				(tracks not_allowed)
				(vias allowed)
				(pads allowed)
				(copperpour not_allowed)
				(footprints allowed)
			)
			(placement
				(enabled no)
				(sheetname "")
			)
			(fill
				(thermal_gap 0.5)
				(thermal_bridge_width 0.5)
				(island_removal_mode 0)
			)
			(polygon
				(pts
					(xy 182.753 -62.23) (xy 183.261 -62.23) (xy 183.261 -62.611) (xy 182.753 -62.611)
				)
			)
		)
		(zone
			(layer "F.Cu")
			(hatch none 0.5)
			(connect_pads
				(clearance 0)
			)
			(min_thickness 0.25)
			(keepout
				(tracks allowed)
				(vias not_allowed)
				(pads allowed)
				(copperpour not_allowed)
				(footprints allowed)
			)
			(placement
				(enabled no)
				(sheetname "")
			)
			(fill
				(thermal_gap 0.5)
				(thermal_bridge_width 0.5)
				(island_removal_mode 0)
			)
			(polygon
				(pts
					(xy 182.753 -62.23) (xy 183.261 -62.23) (xy 183.261 -62.611) (xy 182.753 -62.611)
				)
			)
		)
	)
	(footprint ""
		(layer "F.Cu")
		(at 102.145592 -68.412614 180)
		(property "Reference" "C2D44"
			(at 0 0 180)
			(layer "F.SilkS")
			(hide yes)
			(effects
				(font
					(size 1.27 1.27)
				)
			)
		)
		(property "Value" ""
			(at 0 0 180)
			(layer "F.Fab")
			(effects
				(font
					(size 1.27 1.27)
				)
			)
		)
		(duplicate_pad_numbers_are_jumpers no)
		(fp_poly
			(pts
				(xy -0.4953 -0.2032) (xy 0.4953 -0.2032) (xy 0.4953 1.6002) (xy -0.4953 1.6002)
			)
			(stroke
				(width 0)
				(type default)
			)
			(fill no)
			(layer "F.CrtYd")
		)
		(fp_line
			(start 0.4953 1.6002)
			(end -0.4953 1.6002)
			(stroke
				(width 0.1)
				(type default)
			)
			(layer "F.Fab")
		)
		(fp_line
			(start 0.4953 -0.2032)
			(end 0.4953 1.6002)
			(stroke
				(width 0.1)
				(type default)
			)
			(layer "F.Fab")
		)
		(fp_line
			(start -0.4953 1.6002)
			(end -0.4953 -0.2032)
			(stroke
				(width 0.1)
				(type default)
			)
			(layer "F.Fab")
		)
		(fp_line
			(start -0.4953 -0.2032)
			(end 0.4953 -0.2032)
			(stroke
				(width 0.1)
				(type default)
			)
			(layer "F.Fab")
		)
		(pad "1" smd rect
			(at 0 0 180)
			(size 0.762 0.889)
			(layers "F.Cu" "F.Mask" "F.Paste")
			(net "PVDDQ_GHJ")
		)
		(pad "2" smd rect
			(at 0 1.397 180)
			(size 0.762 0.889)
			(layers "F.Cu" "F.Mask" "F.Paste")
			(net "GND")
		)
		(zone
			(layer "F.Cu")
			(hatch none 0.5)
			(connect_pads
				(clearance 0)
			)
			(min_thickness 0.25)
			(keepout
				(tracks not_allowed)
				(vias allowed)
				(pads allowed)
				(copperpour not_allowed)
				(footprints allowed)
			)
			(placement
				(enabled no)
				(sheetname "")
			)
			(fill
				(thermal_gap 0.5)
				(thermal_bridge_width 0.5)
				(island_removal_mode 0)
			)
			(polygon
				(pts
					(xy 102.526592 -68.857114) (xy 101.764592 -68.857114) (xy 101.764592 -69.365114) (xy 102.526592 -69.365114)
				)
			)
		)
	)
)
